# T6G (Grand Teton) — schematic netlist excerpt (pin names and nets, part order shuffled) for the footprints in the layout excerpt that follows; sources: Cadence DE-HDL packaged netlist, KiCad conversion of 04192023_DAF0TMB3IC0_F0TG_MB_C_brd_V02_OCP.brd

PC1846  Q_CAP  1UF 16V 10% X6S  pkg C0402  page 189 : A = SW_P5V_AUX_FLT ; B = GND

U8003  APX80929SAG7  APX809-29SAG-7 IC  pkg SOT23_123XI  page 147
  GND  = GND
  RESET_L  = P3V3_E1S_PWRGD_0_R1
  VCC  = P3V3_E1S_0_R

PC94  Q_CAP  0.22UF 16V 10% X7R  pkg 0402  page 201 : A = SW_PVDDCR_CPU1_P0_BOOT2_R ; B = SW_PVDDCR_CPU1_P0_BOOTR2

(kicad_pcb
	(version 20260206)
	(generator "pcbnew")
	(generator_version "10.0")
	(general
		(thickness 1.6)
		(legacy_teardrops no)
	)
	(paper "A4")
	(title_block
		(title "04192023_DAF0TMB3IC0_F0TG_MB_C_brd_V02_OCP.brd")
		(comment 1 "Grand Teton / footprints 935-937 of 8354")
	)
	(layers
		(0 "F.Cu" signal "TOP")
		(4 "In1.Cu" signal "GND")
		(6 "In2.Cu" signal "IN1")
		(8 "In3.Cu" signal "GND1")
		(10 "In4.Cu" signal "IN2")
		(12 "In5.Cu" signal "GND2")
		(14 "In6.Cu" signal "IN3")
		(16 "In7.Cu" signal "GND3")
		(18 "In8.Cu" signal "VCC")
		(20 "In9.Cu" signal "VCC1")
		(22 "In10.Cu" signal "GND4")
		(24 "In11.Cu" signal "IN4")
		(26 "In12.Cu" signal "GND5")
		(28 "In13.Cu" signal "IN5")
		(30 "In14.Cu" signal "GND6")
		(32 "In15.Cu" signal "IN6")
		(34 "In16.Cu" signal "GND7")
		(2 "B.Cu" signal "BOTTOM")
		(9 "F.Adhes" user "F.Adhesive")
		(11 "B.Adhes" user "B.Adhesive")
		(13 "F.Paste" user "Package Geometry/Pastemask Top")
		(15 "B.Paste" user "Package Geometry/Pastemask Bottom")
		(5 "F.SilkS" user "Ref Des/Silkscreen Top")
		(7 "B.SilkS" user "Ref Des/Silkscreen Bottom")
		(1 "F.Mask" user "Board Geometry/Soldermask Top")
		(3 "B.Mask" user "Board Geometry/Soldermask Bottom")
		(17 "Dwgs.User" user "User.Drawings")
		(19 "Cmts.User" user "User.Comments")
		(21 "Eco1.User" user "User.Eco1")
		(23 "Eco2.User" user "User.Eco2")
		(25 "Edge.Cuts" user "Board Geometry/Outline")
		(27 "Margin" user)
		(31 "F.CrtYd" user "Package Geometry/Place Bound Top")
		(29 "B.CrtYd" user "Package Geometry/Place Bound Bottom")
		(35 "F.Fab" user "Ref Des/Assembly Top")
		(33 "B.Fab" user "Ref Des/Assembly Bottom")
	)
	(footprint ""
		(layer "F.Cu")
		(at 412.487364 -143.967962 180)
		(property "Reference" "PC1846"
			(at 0 0 180)
			(layer "F.SilkS")
			(hide yes)
			(effects
				(font
					(size 1.27 1.27)
				)
			)
		)
		(property "Value" ""
			(at 0 0 180)
			(layer "F.Fab")
			(effects
				(font
					(size 1.27 1.27)
				)
			)
		)
		(duplicate_pad_numbers_are_jumpers no)
		(fp_line
			(start 0.7874 0.4064)
			(end -0.7874 0.4064)
			(stroke
				(width 0.1524)
				(type default)
			)
			(layer "F.SilkS")
		)
		(fp_line
			(start 0.7874 -0.4064)
			(end 0.7874 0.4064)
			(stroke
				(width 0.1524)
				(type default)
			)
			(layer "F.SilkS")
		)
		(fp_line
			(start -0.7874 0.4064)
			(end -0.7874 -0.4064)
			(stroke
				(width 0.1524)
				(type default)
			)
			(layer "F.SilkS")
		)
		(fp_line
			(start -0.7874 -0.4064)
			(end 0.7874 -0.4064)
			(stroke
				(width 0.1524)
				(type default)
			)
			(layer "F.SilkS")
		)
		(fp_line
			(start 0.67945 0.3048)
			(end 0.120396 0.3048)
			(stroke
				(width 0.1)
				(type default)
			)
			(layer "F.Fab")
		)
		(fp_line
			(start 0.67945 -0.3048)
			(end 0.67945 0.3048)
			(stroke
				(width 0.1)
				(type default)
			)
			(layer "F.Fab")
		)
		(fp_line
			(start 0.12065 -0.2794)
			(end 0.12065 -0.3048)
			(stroke
				(width 0.1)
				(type default)
			)
			(layer "F.Fab")
		)
		(fp_line
			(start 0.12065 -0.3048)
			(end 0.67945 -0.3048)
			(stroke
				(width 0.1)
				(type default)
			)
			(layer "F.Fab")
		)
		(fp_line
			(start 0.120396 0.3048)
			(end 0.120396 0.2794)
			(stroke
				(width 0.1)
				(type default)
			)
			(layer "F.Fab")
		)
		(fp_line
			(start 0.120396 0.2794)
			(end -0.12065 0.2794)
			(stroke
				(width 0.1)
				(type default)
			)
			(layer "F.Fab")
		)
		(fp_line
			(start -0.12065 0.3048)
			(end -0.67945 0.3048)
			(stroke
				(width 0.1)
				(type default)
			)
			(layer "F.Fab")
		)
		(fp_line
			(start -0.12065 0.2794)
			(end -0.12065 0.3048)
			(stroke
				(width 0.1)
				(type default)
			)
			(layer "F.Fab")
		)
		(fp_line
			(start -0.12065 -0.2794)
			(end 0.12065 -0.2794)
			(stroke
				(width 0.1)
				(type default)
			)
			(layer "F.Fab")
		)
		(fp_line
			(start -0.12065 -0.305054)
			(end -0.12065 -0.2794)
			(stroke
				(width 0.1)
				(type default)
			)
			(layer "F.Fab")
		)
		(fp_line
			(start -0.67945 0.3048)
			(end -0.67945 -0.305054)
			(stroke
				(width 0.1)
				(type default)
			)
			(layer "F.Fab")
		)
		(fp_line
			(start -0.67945 -0.305054)
			(end -0.12065 -0.305054)
			(stroke
				(width 0.1)
				(type default)
			)
			(layer "F.Fab")
		)
		(pad "1" smd circle
			(at -0.40005 0 180)
			(size 0 0)
			(layers "F.Cu" "F.Mask" "F.Paste")
			(net "SW_P5V_AUX_FLT")
		)
		(pad "2" smd circle
			(at 0.40005 0 180)
			(size 0 0)
			(layers "F.Cu" "F.Mask" "F.Paste")
			(net "GND")
		)
	)
	(footprint ""
		(layer "F.Cu")
		(at 223.774 -80.137 -90)
		(property "Reference" "U8003"
			(at 1.93294 -2.871978 90)
			(unlocked yes)
			(layer "F.SilkS")
			(effects
				(font
					(size 0.7874 0.5842)
					(thickness 0.1524)
				)
				(justify left)
			)
		)
		(property "Value" ""
			(at 0 0 270)
			(layer "F.Fab")
			(effects
				(font
					(size 1.27 1.27)
				)
			)
		)
		(duplicate_pad_numbers_are_jumpers no)
		(fp_line
			(start -1.759712 1.500124)
			(end -1.759712 -1.500124)
			(stroke
				(width 0.1524)
				(type default)
			)
			(layer "F.SilkS")
		)
		(fp_line
			(start 1.759712 1.500124)
			(end -1.759712 1.500124)
			(stroke
				(width 0.1524)
				(type default)
			)
			(layer "F.SilkS")
		)
		(fp_line
			(start -1.759712 -1.500124)
			(end 1.759712 -1.500124)
			(stroke
				(width 0.1524)
				(type default)
			)
			(layer "F.SilkS")
		)
		(fp_line
			(start 1.759712 -1.500124)
			(end 1.759712 1.500124)
			(stroke
				(width 0.1524)
				(type default)
			)
			(layer "F.SilkS")
		)
		(fp_line
			(start -0.700024 1.500124)
			(end -0.700024 -1.500124)
			(stroke
				(width 0.1)
				(type default)
			)
			(layer "F.Fab")
		)
		(fp_line
			(start 0.700024 1.500124)
			(end -0.700024 1.500124)
			(stroke
				(width 0.1)
				(type default)
			)
			(layer "F.Fab")
		)
		(fp_line
			(start -0.700024 -1.500124)
			(end 0.700024 -1.500124)
			(stroke
				(width 0.1)
				(type default)
			)
			(layer "F.Fab")
		)
		(fp_line
			(start 0.700024 -1.500124)
			(end 0.700024 1.500124)
			(stroke
				(width 0.1)
				(type default)
			)
			(layer "F.Fab")
		)
		(pad "1" smd rect
			(at -1.150112 -0.94996 180)
			(size 0.6604 0.9652)
			(layers "F.Cu" "F.Mask" "F.Paste")
			(net "GND")
		)
		(pad "2" smd rect
			(at -1.150112 0.94996 180)
			(size 0.6604 0.9652)
			(layers "F.Cu" "F.Mask" "F.Paste")
			(net "P3V3_E1S_PWRGD_0_R1")
		)
		(pad "3" smd rect
			(at 1.150112 0 180)
			(size 0.6604 0.9652)
			(layers "F.Cu" "F.Mask" "F.Paste")
			(net "P3V3_E1S_0_R")
		)
	)
	(footprint ""
		(layer "F.Cu")
		(at 328.487278 -339.63991 -90)
		(property "Reference" "PC94"
			(at 0 0 270)
			(layer "F.SilkS")
			(hide yes)
			(effects
				(font
					(size 1.27 1.27)
				)
			)
		)
		(property "Value" ""
			(at 0 0 270)
			(layer "F.Fab")
			(effects
				(font
					(size 1.27 1.27)
				)
			)
		)
		(duplicate_pad_numbers_are_jumpers no)
		(fp_line
			(start -0.7874 0.4064)
			(end -0.7874 -0.4064)
			(stroke
				(width 0.1524)
				(type default)
			)
			(layer "F.SilkS")
		)
		(fp_line
			(start 0.7874 0.4064)
			(end -0.7874 0.4064)
			(stroke
				(width 0.1524)
				(type default)
			)
			(layer "F.SilkS")
		)
		(fp_line
			(start -0.7874 -0.4064)
			(end 0.7874 -0.4064)
			(stroke
				(width 0.1524)
				(type default)
			)
			(layer "F.SilkS")
		)
		(fp_line
			(start 0.7874 -0.4064)
			(end 0.7874 0.4064)
			(stroke
				(width 0.1524)
				(type default)
			)
			(layer "F.SilkS")
		)
		(fp_line
			(start -0.67945 0.3048)
			(end -0.67945 -0.305054)
			(stroke
				(width 0.1)
				(type default)
			)
			(layer "F.Fab")
		)
		(fp_line
			(start -0.12065 0.3048)
			(end -0.67945 0.3048)
			(stroke
				(width 0.1)
				(type default)
			)
			(layer "F.Fab")
		)
		(fp_line
			(start 0.120396 0.3048)
			(end 0.120396 0.2794)
			(stroke
				(width 0.1)
				(type default)
			)
			(layer "F.Fab")
		)
		(fp_line
			(start 0.67945 0.3048)
			(end 0.120396 0.3048)
			(stroke
				(width 0.1)
				(type default)
			)
			(layer "F.Fab")
		)
		(fp_line
			(start -0.12065 0.2794)
			(end -0.12065 0.3048)
			(stroke
				(width 0.1)
				(type default)
			)
			(layer "F.Fab")
		)
		(fp_line
			(start 0.120396 0.2794)
			(end -0.12065 0.2794)
			(stroke
				(width 0.1)
				(type default)
			)
			(layer "F.Fab")
		)
		(fp_line
			(start -0.12065 -0.2794)
			(end 0.12065 -0.2794)
			(stroke
				(width 0.1)
				(type default)
			)
			(layer "F.Fab")
		)
		(fp_line
			(start 0.12065 -0.2794)
			(end 0.12065 -0.3048)
			(stroke
				(width 0.1)
				(type default)
			)
			(layer "F.Fab")
		)
		(fp_line
			(start 0.12065 -0.3048)
			(end 0.67945 -0.3048)
			(stroke
				(width 0.1)
				(type default)
			)
			(layer "F.Fab")
		)
		(fp_line
			(start 0.67945 -0.3048)
			(end 0.67945 0.3048)
			(stroke
				(width 0.1)
				(type default)
			)
			(layer "F.Fab")
		)
		(fp_line
			(start -0.67945 -0.305054)
			(end -0.12065 -0.305054)
			(stroke
				(width 0.1)
				(type default)
			)
			(layer "F.Fab")
		)
		(fp_line
			(start -0.12065 -0.305054)
			(end -0.12065 -0.2794)
			(stroke
				(width 0.1)
				(type default)
			)
			(layer "F.Fab")
		)
		(pad "1" smd circle
			(at -0.40005 0 270)
			(size 0 0)
			(layers "F.Cu" "F.Mask" "F.Paste")
			(net "SW_PVDDCR_CPU1_P0_BOOT2_R")
		)
		(pad "2" smd circle
			(at 0.40005 0 270)
			(size 0 0)
			(layers "F.Cu" "F.Mask" "F.Paste")
			(net "SW_PVDDCR_CPU1_P0_BOOTR2")
		)
	)
)
